(kicad_pcb
	(version 20260206)
	(generator "pcbnew")
	(generator_version "10.0")
	(general
		(thickness 1.6)
		(legacy_teardrops no)
	)
	(paper "A4")
	(title_block
		(title "03242023_DA0F0TMBIJ0_F0T_Motherboard_J_brd_V01_OCP.brd")
		(comment 1 "Grand Teton / footprints 2894-2899 of 6105")
	)
	(layers
		(0 "F.Cu" signal "TOP")
		(4 "In1.Cu" signal "GND")
		(6 "In2.Cu" signal "IN1")
		(8 "In3.Cu" signal "GND1")
		(10 "In4.Cu" signal "IN2")
		(12 "In5.Cu" signal "GND2")
		(14 "In6.Cu" signal "IN3")
		(16 "In7.Cu" signal "GND3")
		(18 "In8.Cu" signal "VCC")
		(20 "In9.Cu" signal "VCC1")
		(22 "In10.Cu" signal "GND4")
		(24 "In11.Cu" signal "IN4")
		(26 "In12.Cu" signal "GND5")
		(28 "In13.Cu" signal "IN5")
		(30 "In14.Cu" signal "GND6")
		(32 "In15.Cu" signal "IN6")
		(34 "In16.Cu" signal "GND7")
		(2 "B.Cu" signal "BOTTOM")
		(9 "F.Adhes" user "F.Adhesive")
		(11 "B.Adhes" user "B.Adhesive")
		(13 "F.Paste" user "Package Geometry/Pastemask Top")
		(15 "B.Paste" user "Package Geometry/Pastemask Bottom")
		(5 "F.SilkS" user "Ref Des/Silkscreen Top")
		(7 "B.SilkS" user "Ref Des/Silkscreen Bottom")
		(1 "F.Mask" user "Board Geometry/Soldermask Top")
		(3 "B.Mask" user "Board Geometry/Soldermask Bottom")
		(17 "Dwgs.User" user "User.Drawings")
		(19 "Cmts.User" user "User.Comments")
		(21 "Eco1.User" user "User.Eco1")
		(23 "Eco2.User" user "User.Eco2")
		(25 "Edge.Cuts" user "Board Geometry/Outline")
		(27 "Margin" user)
		(31 "F.CrtYd" user "Package Geometry/Place Bound Top")
		(29 "B.CrtYd" user "Package Geometry/Place Bound Bottom")
		(35 "F.Fab" user "Ref Des/Assembly Top")
		(33 "B.Fab" user "Ref Des/Assembly Bottom")
	)
	(footprint ""
		(layer "F.Cu")
		(at 348.390464 -357.494332 180)
		(property "Reference" "R2381"
			(at 0 0 180)
			(layer "F.SilkS")
			(hide yes)
			(effects
				(font
					(size 1.27 1.27)
				)
			)
		)
		(property "Value" ""
			(at 0 0 180)
			(layer "F.Fab")
			(effects
				(font
					(size 1.27 1.27)
				)
			)
		)
		(duplicate_pad_numbers_are_jumpers no)
		(fp_line
			(start 0.7874 0.4064)
			(end -0.7874 0.4064)
			(stroke
				(width 0.1524)
				(type default)
			)
			(layer "F.SilkS")
		)
		(fp_line
			(start 0.7874 -0.4064)
			(end 0.7874 0.4064)
			(stroke
				(width 0.1524)
				(type default)
			)
			(layer "F.SilkS")
		)
		(fp_line
			(start -0.7874 0.4064)
			(end -0.7874 -0.4064)
			(stroke
				(width 0.1524)
				(type default)
			)
			(layer "F.SilkS")
		)
		(fp_line
			(start -0.7874 -0.4064)
			(end 0.7874 -0.4064)
			(stroke
				(width 0.1524)
				(type default)
			)
			(layer "F.SilkS")
		)
		(fp_line
			(start 0.67945 0.3048)
			(end 0.120396 0.3048)
			(stroke
				(width 0.1)
				(type default)
			)
			(layer "F.Fab")
		)
		(fp_line
			(start 0.67945 -0.3048)
			(end 0.67945 0.3048)
			(stroke
				(width 0.1)
				(type default)
			)
			(layer "F.Fab")
		)
		(fp_line
			(start 0.12065 -0.2794)
			(end 0.12065 -0.3048)
			(stroke
				(width 0.1)
				(type default)
			)
			(layer "F.Fab")
		)
		(fp_line
			(start 0.12065 -0.3048)
			(end 0.67945 -0.3048)
			(stroke
				(width 0.1)
				(type default)
			)
			(layer "F.Fab")
		)
		(fp_line
			(start 0.120396 0.3048)
			(end 0.120396 0.2794)
			(stroke
				(width 0.1)
				(type default)
			)
			(layer "F.Fab")
		)
		(fp_line
			(start 0.120396 0.2794)
			(end -0.12065 0.2794)
			(stroke
				(width 0.1)
				(type default)
			)
			(layer "F.Fab")
		)
		(fp_line
			(start -0.12065 0.3048)
			(end -0.67945 0.3048)
			(stroke
				(width 0.1)
				(type default)
			)
			(layer "F.Fab")
		)
		(fp_line
			(start -0.12065 0.2794)
			(end -0.12065 0.3048)
			(stroke
				(width 0.1)
				(type default)
			)
			(layer "F.Fab")
		)
		(fp_line
			(start -0.12065 -0.2794)
			(end 0.12065 -0.2794)
			(stroke
				(width 0.1)
				(type default)
			)
			(layer "F.Fab")
		)
		(fp_line
			(start -0.12065 -0.305054)
			(end -0.12065 -0.2794)
			(stroke
				(width 0.1)
				(type default)
			)
			(layer "F.Fab")
		)
		(fp_line
			(start -0.67945 0.3048)
			(end -0.67945 -0.305054)
			(stroke
				(width 0.1)
				(type default)
			)
			(layer "F.Fab")
		)
		(fp_line
			(start -0.67945 -0.305054)
			(end -0.12065 -0.305054)
			(stroke
				(width 0.1)
				(type default)
			)
			(layer "F.Fab")
		)
		(pad "1" smd circle
			(at -0.40005 0 180)
			(size 0 0)
			(layers "F.Cu" "F.Mask" "F.Paste")
			(net "SVID_CLK0_CPU0_R")
		)
		(pad "2" smd circle
			(at 0.40005 0 180)
			(size 0 0)
			(layers "F.Cu" "F.Mask" "F.Paste")
			(net "PVNN_TERM_CPU0")
		)
	)
	(footprint ""
		(layer "F.Cu")
		(at 28.08605 -47.335948)
		(property "Reference" "R3054"
			(at 0 0 0)
			(layer "F.SilkS")
			(hide yes)
			(effects
				(font
					(size 1.27 1.27)
				)
			)
		)
		(property "Value" ""
			(at 0 0 0)
			(layer "F.Fab")
			(effects
				(font
					(size 1.27 1.27)
				)
			)
		)
		(duplicate_pad_numbers_are_jumpers no)
		(fp_line
			(start -0.7874 -0.4064)
			(end 0.7874 -0.4064)
			(stroke
				(width 0.1524)
				(type default)
			)
			(layer "F.SilkS")
		)
		(fp_line
			(start -0.7874 0.4064)
			(end -0.7874 -0.4064)
			(stroke
				(width 0.1524)
				(type default)
			)
			(layer "F.SilkS")
		)
		(fp_line
			(start 0.7874 -0.4064)
			(end 0.7874 0.4064)
			(stroke
				(width 0.1524)
				(type default)
			)
			(layer "F.SilkS")
		)
		(fp_line
			(start 0.7874 0.4064)
			(end -0.7874 0.4064)
			(stroke
				(width 0.1524)
				(type default)
			)
			(layer "F.SilkS")
		)
		(fp_line
			(start -0.67945 -0.305054)
			(end -0.12065 -0.305054)
			(stroke
				(width 0.1)
				(type default)
			)
			(layer "F.Fab")
		)
		(fp_line
			(start -0.67945 0.3048)
			(end -0.67945 -0.305054)
			(stroke
				(width 0.1)
				(type default)
			)
			(layer "F.Fab")
		)
		(fp_line
			(start -0.12065 -0.305054)
			(end -0.12065 -0.2794)
			(stroke
				(width 0.1)
				(type default)
			)
			(layer "F.Fab")
		)
		(fp_line
			(start -0.12065 -0.2794)
			(end 0.12065 -0.2794)
			(stroke
				(width 0.1)
				(type default)
			)
			(layer "F.Fab")
		)
		(fp_line
			(start -0.12065 0.2794)
			(end -0.12065 0.3048)
			(stroke
				(width 0.1)
				(type default)
			)
			(layer "F.Fab")
		)
		(fp_line
			(start -0.12065 0.3048)
			(end -0.67945 0.3048)
			(stroke
				(width 0.1)
				(type default)
			)
			(layer "F.Fab")
		)
		(fp_line
			(start 0.120396 0.2794)
			(end -0.12065 0.2794)
			(stroke
				(width 0.1)
				(type default)
			)
			(layer "F.Fab")
		)
		(fp_line
			(start 0.120396 0.3048)
			(end 0.120396 0.2794)
			(stroke
				(width 0.1)
				(type default)
			)
			(layer "F.Fab")
		)
		(fp_line
			(start 0.12065 -0.3048)
			(end 0.67945 -0.3048)
			(stroke
				(width 0.1)
				(type default)
			)
			(layer "F.Fab")
		)
		(fp_line
			(start 0.12065 -0.2794)
			(end 0.12065 -0.3048)
			(stroke
				(width 0.1)
				(type default)
			)
			(layer "F.Fab")
		)
		(fp_line
			(start 0.67945 -0.3048)
			(end 0.67945 0.3048)
			(stroke
				(width 0.1)
				(type default)
			)
			(layer "F.Fab")
		)
		(fp_line
			(start 0.67945 0.3048)
			(end 0.120396 0.3048)
			(stroke
				(width 0.1)
				(type default)
			)
			(layer "F.Fab")
		)
		(pad "1" smd circle
			(at -0.40005 0)
			(size 0 0)
			(layers "F.Cu" "F.Mask" "F.Paste")
			(net "PWRGD_PS_PWROK_ME_CONN")
		)
		(pad "2" smd circle
			(at 0.40005 0)
			(size 0 0)
			(layers "F.Cu" "F.Mask" "F.Paste")
			(net "PWRGD_PS_PWROK")
		)
	)
	(footprint ""
		(layer "F.Cu")
		(at 85.9028 -36.032948 180)
		(property "Reference" "R1132"
			(at 0 0 180)
			(layer "F.SilkS")
			(hide yes)
			(effects
				(font
					(size 1.27 1.27)
				)
			)
		)
		(property "Value" ""
			(at 0 0 180)
			(layer "F.Fab")
			(effects
				(font
					(size 1.27 1.27)
				)
			)
		)
		(duplicate_pad_numbers_are_jumpers no)
		(fp_line
			(start 0.7874 0.4064)
			(end -0.7874 0.4064)
			(stroke
				(width 0.1524)
				(type default)
			)
			(layer "F.SilkS")
		)
		(fp_line
			(start 0.7874 -0.4064)
			(end 0.7874 0.4064)
			(stroke
				(width 0.1524)
				(type default)
			)
			(layer "F.SilkS")
		)
		(fp_line
			(start -0.7874 0.4064)
			(end -0.7874 -0.4064)
			(stroke
				(width 0.1524)
				(type default)
			)
			(layer "F.SilkS")
		)
		(fp_line
			(start -0.7874 -0.4064)
			(end 0.7874 -0.4064)
			(stroke
				(width 0.1524)
				(type default)
			)
			(layer "F.SilkS")
		)
		(fp_line
			(start 0.67945 0.3048)
			(end 0.120396 0.3048)
			(stroke
				(width 0.1)
				(type default)
			)
			(layer "F.Fab")
		)
		(fp_line
			(start 0.67945 -0.3048)
			(end 0.67945 0.3048)
			(stroke
				(width 0.1)
				(type default)
			)
			(layer "F.Fab")
		)
		(fp_line
			(start 0.12065 -0.2794)
			(end 0.12065 -0.3048)
			(stroke
				(width 0.1)
				(type default)
			)
			(layer "F.Fab")
		)
		(fp_line
			(start 0.12065 -0.3048)
			(end 0.67945 -0.3048)
			(stroke
				(width 0.1)
				(type default)
			)
			(layer "F.Fab")
		)
		(fp_line
			(start 0.120396 0.3048)
			(end 0.120396 0.2794)
			(stroke
				(width 0.1)
				(type default)
			)
			(layer "F.Fab")
		)
		(fp_line
			(start 0.120396 0.2794)
			(end -0.12065 0.2794)
			(stroke
				(width 0.1)
				(type default)
			)
			(layer "F.Fab")
		)
		(fp_line
			(start -0.12065 0.3048)
			(end -0.67945 0.3048)
			(stroke
				(width 0.1)
				(type default)
			)
			(layer "F.Fab")
		)
		(fp_line
			(start -0.12065 0.2794)
			(end -0.12065 0.3048)
			(stroke
				(width 0.1)
				(type default)
			)
			(layer "F.Fab")
		)
		(fp_line
			(start -0.12065 -0.2794)
			(end 0.12065 -0.2794)
			(stroke
				(width 0.1)
				(type default)
			)
			(layer "F.Fab")
		)
		(fp_line
			(start -0.12065 -0.305054)
			(end -0.12065 -0.2794)
			(stroke
				(width 0.1)
				(type default)
			)
			(layer "F.Fab")
		)
		(fp_line
			(start -0.67945 0.3048)
			(end -0.67945 -0.305054)
			(stroke
				(width 0.1)
				(type default)
			)
			(layer "F.Fab")
		)
		(fp_line
			(start -0.67945 -0.305054)
			(end -0.12065 -0.305054)
			(stroke
				(width 0.1)
				(type default)
			)
			(layer "F.Fab")
		)
		(pad "1" smd circle
			(at -0.40005 0 180)
			(size 0 0)
			(layers "F.Cu" "F.Mask" "F.Paste")
			(net "P3V3_AUX")
		)
		(pad "2" smd circle
			(at 0.40005 0 180)
			(size 0 0)
			(layers "F.Cu" "F.Mask" "F.Paste")
			(net "HP_OCP_V3_2_RST_R")
		)
	)
	(footprint ""
		(layer "F.Cu")
		(at 154.65933 -70.26402 90)
		(property "Reference" "R2308"
			(at 0 0 90)
			(layer "F.SilkS")
			(hide yes)
			(effects
				(font
					(size 1.27 1.27)
				)
			)
		)
		(property "Value" ""
			(at 0 0 90)
			(layer "F.Fab")
			(effects
				(font
					(size 1.27 1.27)
				)
			)
		)
		(duplicate_pad_numbers_are_jumpers no)
		(fp_line
			(start 0.7874 -0.4064)
			(end 0.7874 0.4064)
			(stroke
				(width 0.1524)
				(type default)
			)
			(layer "F.SilkS")
		)
		(fp_line
			(start -0.7874 -0.4064)
			(end 0.7874 -0.4064)
			(stroke
				(width 0.1524)
				(type default)
			)
			(layer "F.SilkS")
		)
		(fp_line
			(start 0.7874 0.4064)
			(end -0.7874 0.4064)
			(stroke
				(width 0.1524)
				(type default)
			)
			(layer "F.SilkS")
		)
		(fp_line
			(start -0.7874 0.4064)
			(end -0.7874 -0.4064)
			(stroke
				(width 0.1524)
				(type default)
			)
			(layer "F.SilkS")
		)
		(fp_line
			(start -0.12065 -0.305054)
			(end -0.12065 -0.2794)
			(stroke
				(width 0.1)
				(type default)
			)
			(layer "F.Fab")
		)
		(fp_line
			(start -0.67945 -0.305054)
			(end -0.12065 -0.305054)
			(stroke
				(width 0.1)
				(type default)
			)
			(layer "F.Fab")
		)
		(fp_line
			(start 0.67945 -0.3048)
			(end 0.67945 0.3048)
			(stroke
				(width 0.1)
				(type default)
			)
			(layer "F.Fab")
		)
		(fp_line
			(start 0.12065 -0.3048)
			(end 0.67945 -0.3048)
			(stroke
				(width 0.1)
				(type default)
			)
			(layer "F.Fab")
		)
		(fp_line
			(start 0.12065 -0.2794)
			(end 0.12065 -0.3048)
			(stroke
				(width 0.1)
				(type default)
			)
			(layer "F.Fab")
		)
		(fp_line
			(start -0.12065 -0.2794)
			(end 0.12065 -0.2794)
			(stroke
				(width 0.1)
				(type default)
			)
			(layer "F.Fab")
		)
		(fp_line
			(start 0.120396 0.2794)
			(end -0.12065 0.2794)
			(stroke
				(width 0.1)
				(type default)
			)
			(layer "F.Fab")
		)
		(fp_line
			(start -0.12065 0.2794)
			(end -0.12065 0.3048)
			(stroke
				(width 0.1)
				(type default)
			)
			(layer "F.Fab")
		)
		(fp_line
			(start 0.67945 0.3048)
			(end 0.120396 0.3048)
			(stroke
				(width 0.1)
				(type default)
			)
			(layer "F.Fab")
		)
		(fp_line
			(start 0.120396 0.3048)
			(end 0.120396 0.2794)
			(stroke
				(width 0.1)
				(type default)
			)
			(layer "F.Fab")
		)
		(fp_line
			(start -0.12065 0.3048)
			(end -0.67945 0.3048)
			(stroke
				(width 0.1)
				(type default)
			)
			(layer "F.Fab")
		)
		(fp_line
			(start -0.67945 0.3048)
			(end -0.67945 -0.305054)
			(stroke
				(width 0.1)
				(type default)
			)
			(layer "F.Fab")
		)
		(pad "1" smd circle
			(at -0.40005 0 90)
			(size 0 0)
			(layers "F.Cu" "F.Mask" "F.Paste")
			(net "P3V3_AUX")
		)
		(pad "2" smd circle
			(at 0.40005 0 90)
			(size 0 0)
			(layers "F.Cu" "F.Mask" "F.Paste")
			(net "PCA9543_S3M_ADDR1")
		)
	)
	(footprint ""
		(layer "F.Cu")
		(at 39.827454 -109.444282 180)
		(property "Reference" "R3686"
			(at 0 0 180)
			(layer "F.SilkS")
			(hide yes)
			(effects
				(font
					(size 1.27 1.27)
				)
			)
		)
		(property "Value" ""
			(at 0 0 180)
			(layer "F.Fab")
			(effects
				(font
					(size 1.27 1.27)
				)
			)
		)
		(duplicate_pad_numbers_are_jumpers no)
		(fp_line
			(start 0.7874 0.4064)
			(end -0.7874 0.4064)
			(stroke
				(width 0.1524)
				(type default)
			)
			(layer "F.SilkS")
		)
		(fp_line
			(start 0.7874 -0.4064)
			(end 0.7874 0.4064)
			(stroke
				(width 0.1524)
				(type default)
			)
			(layer "F.SilkS")
		)
		(fp_line
			(start -0.7874 0.4064)
			(end -0.7874 -0.4064)
			(stroke
				(width 0.1524)
				(type default)
			)
			(layer "F.SilkS")
		)
		(fp_line
			(start -0.7874 -0.4064)
			(end 0.7874 -0.4064)
			(stroke
				(width 0.1524)
				(type default)
			)
			(layer "F.SilkS")
		)
		(fp_line
			(start 0.67945 0.3048)
			(end 0.120396 0.3048)
			(stroke
				(width 0.1)
				(type default)
			)
			(layer "F.Fab")
		)
		(fp_line
			(start 0.67945 -0.3048)
			(end 0.67945 0.3048)
			(stroke
				(width 0.1)
				(type default)
			)
			(layer "F.Fab")
		)
		(fp_line
			(start 0.12065 -0.2794)
			(end 0.12065 -0.3048)
			(stroke
				(width 0.1)
				(type default)
			)
			(layer "F.Fab")
		)
		(fp_line
			(start 0.12065 -0.3048)
			(end 0.67945 -0.3048)
			(stroke
				(width 0.1)
				(type default)
			)
			(layer "F.Fab")
		)
		(fp_line
			(start 0.120396 0.3048)
			(end 0.120396 0.2794)
			(stroke
				(width 0.1)
				(type default)
			)
			(layer "F.Fab")
		)
		(fp_line
			(start 0.120396 0.2794)
			(end -0.12065 0.2794)
			(stroke
				(width 0.1)
				(type default)
			)
			(layer "F.Fab")
		)
		(fp_line
			(start -0.12065 0.3048)
			(end -0.67945 0.3048)
			(stroke
				(width 0.1)
				(type default)
			)
			(layer "F.Fab")
		)
		(fp_line
			(start -0.12065 0.2794)
			(end -0.12065 0.3048)
			(stroke
				(width 0.1)
				(type default)
			)
			(layer "F.Fab")
		)
		(fp_line
			(start -0.12065 -0.2794)
			(end 0.12065 -0.2794)
			(stroke
				(width 0.1)
				(type default)
			)
			(layer "F.Fab")
		)
		(fp_line
			(start -0.12065 -0.305054)
			(end -0.12065 -0.2794)
			(stroke
				(width 0.1)
				(type default)
			)
			(layer "F.Fab")
		)
		(fp_line
			(start -0.67945 0.3048)
			(end -0.67945 -0.305054)
			(stroke
				(width 0.1)
				(type default)
			)
			(layer "F.Fab")
		)
		(fp_line
			(start -0.67945 -0.305054)
			(end -0.12065 -0.305054)
			(stroke
				(width 0.1)
				(type default)
			)
			(layer "F.Fab")
		)
		(pad "1" smd rect
			(at -0.40005 0)
			(size 0.4572 0.508)
			(layers "F.Cu" "F.Mask" "F.Paste")
			(net "P5V_ADC")
		)
		(pad "2" smd rect
			(at 0.40005 0)
			(size 0.4572 0.508)
			(layers "F.Cu" "F.Mask" "F.Paste")
			(net "P5V_ADC_TIC")
		)
	)
	(footprint ""
		(layer "F.Cu")
		(at 89.95283 -74.819764 -90)
		(property "Reference" "R3102"
			(at 0 0 270)
			(layer "F.SilkS")
			(hide yes)
			(effects
				(font
					(size 1.27 1.27)
				)
			)
		)
		(property "Value" ""
			(at 0 0 270)
			(layer "F.Fab")
			(effects
				(font
					(size 1.27 1.27)
				)
			)
		)
		(duplicate_pad_numbers_are_jumpers no)
		(fp_line
			(start -0.7874 0.4064)
			(end -0.7874 -0.4064)
			(stroke
				(width 0.1524)
				(type default)
			)
			(layer "F.SilkS")
		)
		(fp_line
			(start 0.7874 0.4064)
			(end -0.7874 0.4064)
			(stroke
				(width 0.1524)
				(type default)
			)
			(layer "F.SilkS")
		)
		(fp_line
			(start -0.7874 -0.4064)
			(end 0.7874 -0.4064)
			(stroke
				(width 0.1524)
				(type default)
			)
			(layer "F.SilkS")
		)
		(fp_line
			(start 0.7874 -0.4064)
			(end 0.7874 0.4064)
			(stroke
				(width 0.1524)
				(type default)
			)
			(layer "F.SilkS")
		)
		(fp_line
			(start -0.67945 0.3048)
			(end -0.67945 -0.305054)
			(stroke
				(width 0.1)
				(type default)
			)
			(layer "F.Fab")
		)
		(fp_line
			(start -0.12065 0.3048)
			(end -0.67945 0.3048)
			(stroke
				(width 0.1)
				(type default)
			)
			(layer "F.Fab")
		)
		(fp_line
			(start 0.120396 0.3048)
			(end 0.120396 0.2794)
			(stroke
				(width 0.1)
				(type default)
			)
			(layer "F.Fab")
		)
		(fp_line
			(start 0.67945 0.3048)
			(end 0.120396 0.3048)
			(stroke
				(width 0.1)
				(type default)
			)
			(layer "F.Fab")
		)
		(fp_line
			(start -0.12065 0.2794)
			(end -0.12065 0.3048)
			(stroke
				(width 0.1)
				(type default)
			)
			(layer "F.Fab")
		)
		(fp_line
			(start 0.120396 0.2794)
			(end -0.12065 0.2794)
			(stroke
				(width 0.1)
				(type default)
			)
			(layer "F.Fab")
		)
		(fp_line
			(start -0.12065 -0.2794)
			(end 0.12065 -0.2794)
			(stroke
				(width 0.1)
				(type default)
			)
			(layer "F.Fab")
		)
		(fp_line
			(start 0.12065 -0.2794)
			(end 0.12065 -0.3048)
			(stroke
				(width 0.1)
				(type default)
			)
			(layer "F.Fab")
		)
		(fp_line
			(start 0.12065 -0.3048)
			(end 0.67945 -0.3048)
			(stroke
				(width 0.1)
				(type default)
			)
			(layer "F.Fab")
		)
		(fp_line
			(start 0.67945 -0.3048)
			(end 0.67945 0.3048)
			(stroke
				(width 0.1)
				(type default)
			)
			(layer "F.Fab")
		)
		(fp_line
			(start -0.67945 -0.305054)
			(end -0.12065 -0.305054)
			(stroke
				(width 0.1)
				(type default)
			)
			(layer "F.Fab")
		)
		(fp_line
			(start -0.12065 -0.305054)
			(end -0.12065 -0.2794)
			(stroke
				(width 0.1)
				(type default)
			)
			(layer "F.Fab")
		)
		(pad "1" smd circle
			(at -0.40005 0 270)
			(size 0 0)
			(layers "F.Cu" "F.Mask" "F.Paste")
			(net "LED_P5V")
		)
		(pad "2" smd circle
			(at 0.40005 0 270)
			(size 0 0)
			(layers "F.Cu" "F.Mask" "F.Paste")
			(net "P5V")
		)
	)
)
